(kicad_pcb
	(version 20260206)
	(generator "pcbnew")
	(generator_version "10.0")
	(general
		(thickness 1.6)
		(legacy_teardrops no)
	)
	(paper "A4")
	(title_block
		(title "Bryce Canyon_R.DPB_16317-1_OCP.brd")
		(comment 1 "Bryce Canyon / footprints 1322-1328 of 2099")
	)
	(layers
		(0 "F.Cu" signal "TOP")
		(4 "In1.Cu" signal "L2GND")
		(6 "In2.Cu" signal "L3")
		(8 "In3.Cu" signal "L4VCC")
		(10 "In4.Cu" signal "L5VCC")
		(12 "In5.Cu" signal "L6")
		(14 "In6.Cu" signal "L7GND")
		(2 "B.Cu" signal "BOTTOM")
		(9 "F.Adhes" user "F.Adhesive")
		(11 "B.Adhes" user "B.Adhesive")
		(13 "F.Paste" user "Package Geometry/Pastemask Top")
		(15 "B.Paste" user "Package Geometry/Pastemask Bottom")
		(5 "F.SilkS" user "Ref Des/Silkscreen Top")
		(7 "B.SilkS" user "Ref Des/Silkscreen Bottom")
		(1 "F.Mask" user "Board Geometry/Soldermask Top")
		(3 "B.Mask" user "Board Geometry/Soldermask Bottom")
		(17 "Dwgs.User" user "User.Drawings")
		(19 "Cmts.User" user "User.Comments")
		(21 "Eco1.User" user "User.Eco1")
		(23 "Eco2.User" user "User.Eco2")
		(25 "Edge.Cuts" user "Board Geometry/Outline")
		(27 "Margin" user)
		(31 "F.CrtYd" user "Package Geometry/Place Bound Top")
		(29 "B.CrtYd" user "Package Geometry/Place Bound Bottom")
		(35 "F.Fab" user "Ref Des/Assembly Top")
		(33 "B.Fab" user "Ref Des/Assembly Bottom")
	)
	(footprint ""
		(layer "F.Cu")
		(at 326.992996 -368.935 -90)
		(property "Reference" "R947"
			(at 0 0 270)
			(layer "F.SilkS")
			(hide yes)
			(effects
				(font
					(size 1.27 1.27)
				)
			)
		)
		(property "Value" "10KR2F-2-GP"
			(at 0.064008 -3.993896 270)
			(unlocked yes)
			(layer "F.Fab")
			(hide yes)
			(effects
				(font
					(size 1.016 1.016)
					(thickness 0.1524)
				)
			)
		)
		(property "Device Type" "R402H16"
			(at 0.064008 -5.517896 270)
			(unlocked yes)
			(layer "F.Fab")
			(hide yes)
			(effects
				(font
					(size 1.016 1.016)
					(thickness 0.1524)
				)
			)
		)
		(duplicate_pad_numbers_are_jumpers no)
		(fp_line
			(start -0.508 -0.9398)
			(end -0.508 0.9398)
			(stroke
				(width 0.1524)
				(type default)
			)
			(layer "F.SilkS")
		)
		(fp_line
			(start 0.508 -0.9398)
			(end -0.508 -0.9398)
			(stroke
				(width 0.1524)
				(type default)
			)
			(layer "F.SilkS")
		)
		(fp_rect
			(start -0.508 0.9398)
			(end 0.508 -0.9398)
			(stroke
				(width 0)
				(type default)
			)
			(fill no)
			(layer "F.CrtYd")
		)
		(fp_rect
			(start -0.508 0.9398)
			(end 0.508 -0.9398)
			(stroke
				(width 0)
				(type default)
			)
			(fill no)
			(layer "F.Fab")
		)
		(pad "1" smd custom
			(at 0 -0.4445 270)
			(size 0.1397 0.1397)
			(layers "F.Cu" "F.Mask" "F.Paste")
			(net "GND")
			(options
				(clearance outline)
				(anchor circle)
			)
			(primitives
				(gr_poly
					(pts
						(arc
							(start -0.1778 -0.2794)
							(mid -0.249642 -0.249642)
							(end -0.2794 -0.1778)
						)
						(arc
							(start -0.2794 0.1778)
							(mid -0.249642 0.249642)
							(end -0.1778 0.2794)
						)
						(arc
							(start 0.1778 0.2794)
							(mid 0.249642 0.249642)
							(end 0.2794 0.1778)
						)
						(arc
							(start 0.2794 -0.1778)
							(mid 0.249642 -0.249642)
							(end 0.1778 -0.2794)
						)
					)
					(width 0)
					(fill yes)
				)
			)
		)
		(pad "2" smd custom
			(at 0 0.4445 270)
			(size 0.1397 0.1397)
			(layers "F.Cu" "F.Mask" "F.Paste")
			(net "FANTACH_R2")
			(options
				(clearance outline)
				(anchor circle)
			)
			(primitives
				(gr_poly
					(pts
						(arc
							(start -0.1778 -0.2794)
							(mid -0.249642 -0.249642)
							(end -0.2794 -0.1778)
						)
						(arc
							(start -0.2794 0.1778)
							(mid -0.249642 0.249642)
							(end -0.1778 0.2794)
						)
						(arc
							(start 0.1778 0.2794)
							(mid 0.249642 0.249642)
							(end 0.2794 0.1778)
						)
						(arc
							(start 0.2794 -0.1778)
							(mid 0.249642 -0.249642)
							(end 0.1778 -0.2794)
						)
					)
					(width 0)
					(fill yes)
				)
			)
		)
	)
	(footprint ""
		(layer "F.Cu")
		(at 20.447 -19.558 180)
		(property "Reference" "Q119"
			(at 0 0 180)
			(layer "F.SilkS")
			(hide yes)
			(effects
				(font
					(size 1.27 1.27)
				)
			)
		)
		(property "Value" "2N7002KDW-GP"
			(at -2.3622 -8.2042 180)
			(unlocked yes)
			(layer "F.Fab")
			(hide yes)
			(effects
				(font
					(size 1.016 1.016)
					(thickness 0.1524)
				)
			)
		)
		(property "Device Type" "SOT-363H44"
			(at -2.3622 -10.1092 180)
			(unlocked yes)
			(layer "F.Fab")
			(hide yes)
			(effects
				(font
					(size 1.016 1.016)
					(thickness 0.1524)
				)
			)
		)
		(duplicate_pad_numbers_are_jumpers no)
		(fp_line
			(start 1.4478 1.7018)
			(end 1.4478 -1.7018)
			(stroke
				(width 0.1524)
				(type default)
			)
			(layer "F.SilkS")
		)
		(fp_line
			(start 1.4478 -1.7018)
			(end -1.4478 -1.7018)
			(stroke
				(width 0.1524)
				(type default)
			)
			(layer "F.SilkS")
		)
		(fp_line
			(start -1.27 1.524)
			(end -1.27 0.6604)
			(stroke
				(width 0.4826)
				(type default)
			)
			(layer "F.SilkS")
		)
		(fp_line
			(start -1.4478 1.7018)
			(end 1.4478 1.7018)
			(stroke
				(width 0.1524)
				(type default)
			)
			(layer "F.SilkS")
		)
		(fp_line
			(start -1.4478 -1.7018)
			(end -1.4478 1.7018)
			(stroke
				(width 0.1524)
				(type default)
			)
			(layer "F.SilkS")
		)
		(fp_poly
			(pts
				(xy -1.524 -1.778) (xy 1.524 -1.778) (xy 1.524 1.778) (xy -1.524 1.778)
			)
			(stroke
				(width 0)
				(type default)
			)
			(fill no)
			(layer "F.CrtYd")
		)
		(fp_poly
			(pts
				(xy -1.524 -1.778) (xy 1.524 -1.778) (xy 1.524 1.778) (xy -1.524 1.778)
			)
			(stroke
				(width 0)
				(type default)
			)
			(fill no)
			(layer "F.Fab")
		)
		(pad "1" smd rect
			(at -0.65024 0.9398 180)
			(size 0.4064 1.016)
			(layers "F.Cu" "F.Mask" "F.Paste")
			(net "GND")
		)
		(pad "2" smd rect
			(at 0 0.9398 180)
			(size 0.4064 1.016)
			(layers "F.Cu" "F.Mask" "F.Paste")
			(net "SW_PWR_R_HDD24")
		)
		(pad "3" smd rect
			(at 0.65024 0.9398 180)
			(size 0.4064 1.016)
			(layers "F.Cu" "F.Mask" "F.Paste")
			(net "SW_HDD_P24")
		)
		(pad "4" smd rect
			(at 0.65024 -0.9398 180)
			(size 0.4064 1.016)
			(layers "F.Cu" "F.Mask" "F.Paste")
			(net "GND")
		)
		(pad "5" smd rect
			(at 0 -0.9398 180)
			(size 0.4064 1.016)
			(layers "F.Cu" "F.Mask" "F.Paste")
			(net "SW_HDD_G24")
		)
		(pad "6" smd rect
			(at -0.65024 -0.9398 180)
			(size 0.4064 1.016)
			(layers "F.Cu" "F.Mask" "F.Paste")
			(net "SW_HDD_R24")
		)
	)
	(footprint ""
		(layer "F.Cu")
		(at 48.514 -214.249)
		(property "Reference" "R220"
			(at 0 0 0)
			(layer "F.SilkS")
			(hide yes)
			(effects
				(font
					(size 1.27 1.27)
				)
			)
		)
		(property "Value" "130R3F-GP"
			(at -0.0254 -2.5146 0)
			(unlocked yes)
			(layer "F.Fab")
			(hide yes)
			(effects
				(font
					(size 1.016 1.016)
					(thickness 0.1524)
				)
			)
		)
		(property "Device Type" "R603H22"
			(at -0.0254 -4.0386 0)
			(unlocked yes)
			(layer "F.Fab")
			(hide yes)
			(effects
				(font
					(size 1.016 1.016)
					(thickness 0.1524)
				)
			)
		)
		(duplicate_pad_numbers_are_jumpers no)
		(fp_line
			(start -0.4826 0)
			(end -0.2032 0)
			(stroke
				(width 0.2032)
				(type default)
			)
			(layer "F.SilkS")
		)
		(fp_line
			(start 0.2032 0)
			(end 0.4826 0)
			(stroke
				(width 0.2032)
				(type default)
			)
			(layer "F.SilkS")
		)
		(fp_rect
			(start -0.5842 1.3335)
			(end 0.5842 -1.3335)
			(stroke
				(width 0)
				(type default)
			)
			(fill no)
			(layer "F.CrtYd")
		)
		(fp_rect
			(start -0.5842 1.3335)
			(end 0.5842 -1.3335)
			(stroke
				(width 0)
				(type default)
			)
			(fill no)
			(layer "F.Fab")
		)
		(pad "1" smd custom
			(at 0 -0.762)
			(size 0.2159 0.2159)
			(layers "F.Cu" "F.Mask" "F.Paste")
			(net "P5V_B_1")
			(options
				(clearance outline)
				(anchor circle)
			)
			(primitives
				(gr_poly
					(pts
						(arc
							(start -0.3302 -0.4318)
							(mid -0.402042 -0.402042)
							(end -0.4318 -0.3302)
						)
						(arc
							(start -0.4318 0.3302)
							(mid -0.402042 0.402042)
							(end -0.3302 0.4318)
						)
						(arc
							(start 0.3302 0.4318)
							(mid 0.402042 0.402042)
							(end 0.4318 0.3302)
						)
						(arc
							(start 0.4318 -0.3302)
							(mid 0.402042 -0.402042)
							(end 0.3302 -0.4318)
						)
					)
					(width 0)
					(fill yes)
				)
			)
		)
		(pad "2" smd custom
			(at 0 0.762)
			(size 0.2159 0.2159)
			(layers "F.Cu" "F.Mask" "F.Paste")
			(net "FLT_HDD1")
			(options
				(clearance outline)
				(anchor circle)
			)
			(primitives
				(gr_poly
					(pts
						(arc
							(start -0.3302 -0.4318)
							(mid -0.402042 -0.402042)
							(end -0.4318 -0.3302)
						)
						(arc
							(start -0.4318 0.3302)
							(mid -0.402042 0.402042)
							(end -0.3302 0.4318)
						)
						(arc
							(start 0.3302 0.4318)
							(mid 0.402042 0.402042)
							(end 0.4318 0.3302)
						)
						(arc
							(start 0.4318 -0.3302)
							(mid 0.402042 -0.402042)
							(end 0.3302 -0.4318)
						)
					)
					(width 0)
					(fill yes)
				)
			)
		)
	)
	(footprint ""
		(layer "F.Cu")
		(at 133.149594 -363.457236 180)
		(property "Reference" "C526"
			(at 0 0 180)
			(layer "F.SilkS")
			(hide yes)
			(effects
				(font
					(size 1.27 1.27)
				)
			)
		)
		(property "Value" "SCD1U25V2KX-2-GP"
			(at 1.1811 -2.7051 180)
			(unlocked yes)
			(layer "F.Fab")
			(hide yes)
			(effects
				(font
					(size 1.016 1.016)
					(thickness 0.1524)
				)
			)
		)
		(property "Device Type" "C402H22"
			(at 1.1811 -4.2291 180)
			(unlocked yes)
			(layer "F.Fab")
			(hide yes)
			(effects
				(font
					(size 1.016 1.016)
					(thickness 0.1524)
				)
			)
		)
		(duplicate_pad_numbers_are_jumpers no)
		(fp_rect
			(start -0.4318 0.9525)
			(end 0.4318 -0.9525)
			(stroke
				(width 0)
				(type default)
			)
			(fill no)
			(layer "F.CrtYd")
		)
		(fp_rect
			(start -0.4318 0.9525)
			(end 0.4318 -0.9525)
			(stroke
				(width 0)
				(type default)
			)
			(fill no)
			(layer "F.Fab")
		)
		(pad "1" smd custom
			(at 0 -0.4445 180)
			(size 0.1524 0.1524)
			(layers "F.Cu" "F.Mask" "F.Paste")
			(net "P12V_FAN1")
			(options
				(clearance outline)
				(anchor circle)
			)
			(primitives
				(gr_poly
					(pts
						(arc
							(start 0.3048 -0.2032)
							(mid 0.275042 -0.275042)
							(end 0.2032 -0.3048)
						)
						(arc
							(start -0.2032 -0.3048)
							(mid -0.275042 -0.275042)
							(end -0.3048 -0.2032)
						)
						(arc
							(start -0.3048 0.2032)
							(mid -0.275042 0.275042)
							(end -0.2032 0.3048)
						)
						(arc
							(start 0.2032 0.3048)
							(mid 0.275042 0.275042)
							(end 0.3048 0.2032)
						)
					)
					(width 0)
					(fill yes)
				)
			)
		)
		(pad "2" smd custom
			(at 0 0.4445 180)
			(size 0.1524 0.1524)
			(layers "F.Cu" "F.Mask" "F.Paste")
			(net "GND")
			(options
				(clearance outline)
				(anchor circle)
			)
			(primitives
				(gr_poly
					(pts
						(arc
							(start 0.3048 -0.2032)
							(mid 0.275042 -0.275042)
							(end 0.2032 -0.3048)
						)
						(arc
							(start -0.2032 -0.3048)
							(mid -0.275042 -0.275042)
							(end -0.3048 -0.2032)
						)
						(arc
							(start -0.3048 0.2032)
							(mid -0.275042 0.275042)
							(end -0.2032 0.3048)
						)
						(arc
							(start 0.2032 0.3048)
							(mid 0.275042 0.275042)
							(end 0.3048 0.2032)
						)
					)
					(width 0)
					(fill yes)
				)
			)
		)
	)
	(footprint ""
		(layer "F.Cu")
		(at 426.72 -131.318 -90)
		(property "Reference" "Q101"
			(at 0 0 270)
			(layer "F.SilkS")
			(hide yes)
			(effects
				(font
					(size 1.27 1.27)
				)
			)
		)
		(property "Value" "2N7002KDW-GP"
			(at -2.3622 -8.2042 270)
			(unlocked yes)
			(layer "F.Fab")
			(hide yes)
			(effects
				(font
					(size 1.016 1.016)
					(thickness 0.1524)
				)
			)
		)
		(property "Device Type" "SOT-363H44"
			(at -2.3622 -10.1092 270)
			(unlocked yes)
			(layer "F.Fab")
			(hide yes)
			(effects
				(font
					(size 1.016 1.016)
					(thickness 0.1524)
				)
			)
		)
		(duplicate_pad_numbers_are_jumpers no)
		(fp_line
			(start -1.4478 1.7018)
			(end 1.4478 1.7018)
			(stroke
				(width 0.1524)
				(type default)
			)
			(layer "F.SilkS")
		)
		(fp_line
			(start 1.4478 1.7018)
			(end 1.4478 -1.7018)
			(stroke
				(width 0.1524)
				(type default)
			)
			(layer "F.SilkS")
		)
		(fp_line
			(start -1.27 1.524)
			(end -1.27 0.6604)
			(stroke
				(width 0.4826)
				(type default)
			)
			(layer "F.SilkS")
		)
		(fp_line
			(start -1.4478 -1.7018)
			(end -1.4478 1.7018)
			(stroke
				(width 0.1524)
				(type default)
			)
			(layer "F.SilkS")
		)
		(fp_line
			(start 1.4478 -1.7018)
			(end -1.4478 -1.7018)
			(stroke
				(width 0.1524)
				(type default)
			)
			(layer "F.SilkS")
		)
		(fp_poly
			(pts
				(xy -1.524 -1.778) (xy 1.524 -1.778) (xy 1.524 1.778) (xy -1.524 1.778)
			)
			(stroke
				(width 0)
				(type default)
			)
			(fill no)
			(layer "F.CrtYd")
		)
		(fp_poly
			(pts
				(xy -1.524 -1.778) (xy 1.524 -1.778) (xy 1.524 1.778) (xy -1.524 1.778)
			)
			(stroke
				(width 0)
				(type default)
			)
			(fill no)
			(layer "F.Fab")
		)
		(pad "1" smd rect
			(at -0.65024 0.9398 270)
			(size 0.4064 1.016)
			(layers "F.Cu" "F.Mask" "F.Paste")
			(net "GND")
		)
		(pad "2" smd rect
			(at 0 0.9398 270)
			(size 0.4064 1.016)
			(layers "F.Cu" "F.Mask" "F.Paste")
			(net "SW_PWR_R_HDD21")
		)
		(pad "3" smd rect
			(at 0.65024 0.9398 270)
			(size 0.4064 1.016)
			(layers "F.Cu" "F.Mask" "F.Paste")
			(net "SW_HDD_P21")
		)
		(pad "4" smd rect
			(at 0.65024 -0.9398 270)
			(size 0.4064 1.016)
			(layers "F.Cu" "F.Mask" "F.Paste")
			(net "GND")
		)
		(pad "5" smd rect
			(at 0 -0.9398 270)
			(size 0.4064 1.016)
			(layers "F.Cu" "F.Mask" "F.Paste")
			(net "SW_HDD_G21")
		)
		(pad "6" smd rect
			(at -0.65024 -0.9398 270)
			(size 0.4064 1.016)
			(layers "F.Cu" "F.Mask" "F.Paste")
			(net "SW_HDD_R21")
		)
	)
	(footprint ""
		(layer "F.Cu")
		(at 415.3662 -31.6484 180)
		(property "Reference" "R829"
			(at 0 0 180)
			(layer "F.SilkS")
			(hide yes)
			(effects
				(font
					(size 1.27 1.27)
				)
			)
		)
		(property "Value" "10KR2F-2-GP"
			(at 0.064008 -3.993896 180)
			(unlocked yes)
			(layer "F.Fab")
			(hide yes)
			(effects
				(font
					(size 1.016 1.016)
					(thickness 0.1524)
				)
			)
		)
		(property "Device Type" "R402H16"
			(at 0.064008 -5.517896 180)
			(unlocked yes)
			(layer "F.Fab")
			(hide yes)
			(effects
				(font
					(size 1.016 1.016)
					(thickness 0.1524)
				)
			)
		)
		(duplicate_pad_numbers_are_jumpers no)
		(fp_line
			(start 0.508 -0.9398)
			(end -0.508 -0.9398)
			(stroke
				(width 0.1524)
				(type default)
			)
			(layer "F.SilkS")
		)
		(fp_line
			(start -0.508 -0.9398)
			(end -0.508 0.9398)
			(stroke
				(width 0.1524)
				(type default)
			)
			(layer "F.SilkS")
		)
		(fp_rect
			(start -0.508 0.9398)
			(end 0.508 -0.9398)
			(stroke
				(width 0)
				(type default)
			)
			(fill no)
			(layer "F.CrtYd")
		)
		(fp_rect
			(start -0.508 0.9398)
			(end 0.508 -0.9398)
			(stroke
				(width 0)
				(type default)
			)
			(fill no)
			(layer "F.Fab")
		)
		(pad "1" smd custom
			(at 0 -0.4445 180)
			(size 0.1397 0.1397)
			(layers "F.Cu" "F.Mask" "F.Paste")
			(net "P3V3_STBY_B")
			(options
				(clearance outline)
				(anchor circle)
			)
			(primitives
				(gr_poly
					(pts
						(arc
							(start -0.1778 -0.2794)
							(mid -0.249642 -0.249642)
							(end -0.2794 -0.1778)
						)
						(arc
							(start -0.2794 0.1778)
							(mid -0.249642 0.249642)
							(end -0.1778 0.2794)
						)
						(arc
							(start 0.1778 0.2794)
							(mid 0.249642 0.249642)
							(end 0.2794 0.1778)
						)
						(arc
							(start 0.2794 -0.1778)
							(mid 0.249642 -0.249642)
							(end 0.1778 -0.2794)
						)
					)
					(width 0)
					(fill yes)
				)
			)
		)
		(pad "2" smd custom
			(at 0 0.4445 180)
			(size 0.1397 0.1397)
			(layers "F.Cu" "F.Mask" "F.Paste")
			(net "HDD_PRSNT_33")
			(options
				(clearance outline)
				(anchor circle)
			)
			(primitives
				(gr_poly
					(pts
						(arc
							(start -0.1778 -0.2794)
							(mid -0.249642 -0.249642)
							(end -0.2794 -0.1778)
						)
						(arc
							(start -0.2794 0.1778)
							(mid -0.249642 0.249642)
							(end -0.1778 0.2794)
						)
						(arc
							(start 0.1778 0.2794)
							(mid 0.249642 0.249642)
							(end 0.2794 0.1778)
						)
						(arc
							(start 0.2794 -0.1778)
							(mid 0.249642 -0.249642)
							(end 0.1778 -0.2794)
						)
					)
					(width 0)
					(fill yes)
				)
			)
		)
	)
	(footprint ""
		(layer "F.Cu")
		(at 248.285 -310.134 -90)
		(property "Reference" "R1185"
			(at 0 0 270)
			(layer "F.SilkS")
			(hide yes)
			(effects
				(font
					(size 1.27 1.27)
				)
			)
		)
		(property "Value" "0R2J-2-GP"
			(at 0.064008 -3.993896 270)
			(unlocked yes)
			(layer "F.Fab")
			(hide yes)
			(effects
				(font
					(size 1.016 1.016)
					(thickness 0.1524)
				)
			)
		)
		(property "Device Type" "R402H16"
			(at 0.064008 -5.517896 270)
			(unlocked yes)
			(layer "F.Fab")
			(hide yes)
			(effects
				(font
					(size 1.016 1.016)
					(thickness 0.1524)
				)
			)
		)
		(duplicate_pad_numbers_are_jumpers no)
		(fp_line
			(start -0.508 -0.9398)
			(end -0.508 0.9398)
			(stroke
				(width 0.1524)
				(type default)
			)
			(layer "F.SilkS")
		)
		(fp_line
			(start 0.508 -0.9398)
			(end -0.508 -0.9398)
			(stroke
				(width 0.1524)
				(type default)
			)
			(layer "F.SilkS")
		)
		(fp_rect
			(start -0.508 0.9398)
			(end 0.508 -0.9398)
			(stroke
				(width 0)
				(type default)
			)
			(fill no)
			(layer "F.CrtYd")
		)
		(fp_rect
			(start -0.508 0.9398)
			(end 0.508 -0.9398)
			(stroke
				(width 0)
				(type default)
			)
			(fill no)
			(layer "F.Fab")
		)
		(pad "1" smd custom
			(at 0 -0.4445 270)
			(size 0.1397 0.1397)
			(layers "F.Cu" "F.Mask" "F.Paste")
			(net "P3V3_STBY_A")
			(options
				(clearance outline)
				(anchor circle)
			)
			(primitives
				(gr_poly
					(pts
						(arc
							(start -0.1778 -0.2794)
							(mid -0.249642 -0.249642)
							(end -0.2794 -0.1778)
						)
						(arc
							(start -0.2794 0.1778)
							(mid -0.249642 0.249642)
							(end -0.1778 0.2794)
						)
						(arc
							(start 0.1778 0.2794)
							(mid 0.249642 0.249642)
							(end 0.2794 0.1778)
						)
						(arc
							(start 0.2794 -0.1778)
							(mid 0.249642 -0.249642)
							(end 0.1778 -0.2794)
						)
					)
					(width 0)
					(fill yes)
				)
			)
		)
		(pad "2" smd custom
			(at 0 0.4445 270)
			(size 0.1397 0.1397)
			(layers "F.Cu" "F.Mask" "F.Paste")
			(net "MAX31790_A_PWM_ST1")
			(options
				(clearance outline)
				(anchor circle)
			)
			(primitives
				(gr_poly
					(pts
						(arc
							(start -0.1778 -0.2794)
							(mid -0.249642 -0.249642)
							(end -0.2794 -0.1778)
						)
						(arc
							(start -0.2794 0.1778)
							(mid -0.249642 0.249642)
							(end -0.1778 0.2794)
						)
						(arc
							(start 0.1778 0.2794)
							(mid 0.249642 0.249642)
							(end 0.2794 0.1778)
						)
						(arc
							(start 0.2794 -0.1778)
							(mid 0.249642 -0.249642)
							(end 0.1778 -0.2794)
						)
					)
					(width 0)
					(fill yes)
				)
			)
		)
	)
)
